(kicad_pcb
	(version 20260206)
	(generator "pcbnew")
	(generator_version "10.0")
	(general
		(thickness 1.6)
		(legacy_teardrops no)
	)
	(paper "A4")
	(title_block
		(title "04192023_DAF0TMB3IC0_F0TG_MB_C_brd_V02_OCP.brd")
		(comment 1 "Grand Teton / footprints 993-994 of 8354")
	)
	(layers
		(0 "F.Cu" signal "TOP")
		(4 "In1.Cu" signal "GND")
		(6 "In2.Cu" signal "IN1")
		(8 "In3.Cu" signal "GND1")
		(10 "In4.Cu" signal "IN2")
		(12 "In5.Cu" signal "GND2")
		(14 "In6.Cu" signal "IN3")
		(16 "In7.Cu" signal "GND3")
		(18 "In8.Cu" signal "VCC")
		(20 "In9.Cu" signal "VCC1")
		(22 "In10.Cu" signal "GND4")
		(24 "In11.Cu" signal "IN4")
		(26 "In12.Cu" signal "GND5")
		(28 "In13.Cu" signal "IN5")
		(30 "In14.Cu" signal "GND6")
		(32 "In15.Cu" signal "IN6")
		(34 "In16.Cu" signal "GND7")
		(2 "B.Cu" signal "BOTTOM")
		(9 "F.Adhes" user "F.Adhesive")
		(11 "B.Adhes" user "B.Adhesive")
		(13 "F.Paste" user "Package Geometry/Pastemask Top")
		(15 "B.Paste" user "Package Geometry/Pastemask Bottom")
		(5 "F.SilkS" user "Ref Des/Silkscreen Top")
		(7 "B.SilkS" user "Ref Des/Silkscreen Bottom")
		(1 "F.Mask" user "Board Geometry/Soldermask Top")
		(3 "B.Mask" user "Board Geometry/Soldermask Bottom")
		(17 "Dwgs.User" user "User.Drawings")
		(19 "Cmts.User" user "User.Comments")
		(21 "Eco1.User" user "User.Eco1")
		(23 "Eco2.User" user "User.Eco2")
		(25 "Edge.Cuts" user "Board Geometry/Outline")
		(27 "Margin" user)
		(31 "F.CrtYd" user "Package Geometry/Place Bound Top")
		(29 "B.CrtYd" user "Package Geometry/Place Bound Bottom")
		(35 "F.Fab" user "Ref Des/Assembly Top")
		(33 "B.Fab" user "Ref Des/Assembly Bottom")
	)
	(footprint ""
		(layer "F.Cu")
		(at 162.22853 -348.553278 -90)
		(property "Reference" "PU54"
			(at 1.566926 -7.369048 90)
			(unlocked yes)
			(layer "F.SilkS")
			(effects
				(font
					(size 0.7874 0.5842)
					(thickness 0.1524)
				)
				(justify left)
			)
		)
		(property "Value" ""
			(at 0 0 270)
			(layer "F.Fab")
			(effects
				(font
					(size 1.27 1.27)
				)
			)
		)
		(duplicate_pad_numbers_are_jumpers no)
		(fp_line
			(start 1.778 3.6322)
			(end 1.778 2.8702)
			(stroke
				(width 0.1524)
				(type default)
			)
			(layer "F.SilkS")
		)
		(fp_line
			(start -0.2032 2.8829)
			(end -0.2032 3.2639)
			(stroke
				(width 0.1524)
				(type default)
			)
			(layer "F.SilkS")
		)
		(fp_line
			(start -2.500122 2.500122)
			(end -2.500122 2.018538)
			(stroke
				(width 0.1524)
				(type default)
			)
			(layer "F.SilkS")
		)
		(fp_line
			(start -2.015998 2.500122)
			(end -2.500122 2.500122)
			(stroke
				(width 0.1524)
				(type default)
			)
			(layer "F.SilkS")
		)
		(fp_line
			(start 2.500122 2.500122)
			(end 2.015998 2.500122)
			(stroke
				(width 0.1524)
				(type default)
			)
			(layer "F.SilkS")
		)
		(fp_line
			(start 2.500122 2.015998)
			(end 2.500122 2.500122)
			(stroke
				(width 0.1524)
				(type default)
			)
			(layer "F.SilkS")
		)
		(fp_line
			(start -3.084322 1.8034)
			(end -2.8956 1.8034)
			(stroke
				(width 0.1524)
				(type default)
			)
			(layer "F.SilkS")
		)
		(fp_line
			(start 2.8829 0.2032)
			(end 3.2639 0.2032)
			(stroke
				(width 0.1524)
				(type default)
			)
			(layer "F.SilkS")
		)
		(fp_line
			(start -3.2639 -0.1778)
			(end -2.8829 -0.1778)
			(stroke
				(width 0.1524)
				(type default)
			)
			(layer "F.SilkS")
		)
		(fp_line
			(start 2.8702 -1.778)
			(end 3.6322 -1.778)
			(stroke
				(width 0.1524)
				(type default)
			)
			(layer "F.SilkS")
		)
		(fp_line
			(start -2.500122 -2.015998)
			(end -2.500122 -2.500122)
			(stroke
				(width 0.1524)
				(type default)
			)
			(layer "F.SilkS")
		)
		(fp_line
			(start -2.500122 -2.500122)
			(end -2.015998 -2.500122)
			(stroke
				(width 0.1524)
				(type default)
			)
			(layer "F.SilkS")
		)
		(fp_line
			(start 2.015998 -2.500122)
			(end 2.500122 -2.500122)
			(stroke
				(width 0.1524)
				(type default)
			)
			(layer "F.SilkS")
		)
		(fp_line
			(start 2.500122 -2.500122)
			(end 2.500122 -2.015998)
			(stroke
				(width 0.1524)
				(type default)
			)
			(layer "F.SilkS")
		)
		(fp_line
			(start -1.8034 -2.8702)
			(end -1.8034 -3.6322)
			(stroke
				(width 0.1524)
				(type default)
			)
			(layer "F.SilkS")
		)
		(fp_line
			(start 0.1778 -3.2385)
			(end 0.1778 -2.8575)
			(stroke
				(width 0.1524)
				(type default)
			)
			(layer "F.SilkS")
		)
		(fp_poly
			(pts
				(xy -2.606294 -2.945638) (xy -2.623058 -2.293874) (xy -3.13436 -2.698496)
			)
			(stroke
				(width 0)
				(type default)
			)
			(fill yes)
			(layer "F.SilkS")
		)
		(fp_line
			(start 1.778 3.6322)
			(end 1.778 2.8702)
			(stroke
				(width 0.1)
				(type default)
			)
			(layer "F.Fab")
		)
		(fp_line
			(start -0.2032 2.8829)
			(end -0.2032 3.2639)
			(stroke
				(width 0.1)
				(type default)
			)
			(layer "F.Fab")
		)
		(fp_line
			(start -2.500122 2.500122)
			(end -2.500122 -2.500122)
			(stroke
				(width 0.1)
				(type default)
			)
			(layer "F.Fab")
		)
		(fp_line
			(start 2.500122 2.500122)
			(end -2.500122 2.500122)
			(stroke
				(width 0.1)
				(type default)
			)
			(layer "F.Fab")
		)
		(fp_line
			(start -3.6576 1.8034)
			(end -2.8956 1.8034)
			(stroke
				(width 0.1)
				(type default)
			)
			(layer "F.Fab")
		)
		(fp_line
			(start 2.8829 0.2032)
			(end 3.2639 0.2032)
			(stroke
				(width 0.1)
				(type default)
			)
			(layer "F.Fab")
		)
		(fp_line
			(start -3.2639 -0.1778)
			(end -2.8829 -0.1778)
			(stroke
				(width 0.1)
				(type default)
			)
			(layer "F.Fab")
		)
		(fp_line
			(start 2.8702 -1.778)
			(end 3.6322 -1.778)
			(stroke
				(width 0.1)
				(type default)
			)
			(layer "F.Fab")
		)
		(fp_line
			(start -2.500122 -2.500122)
			(end 2.500122 -2.500122)
			(stroke
				(width 0.1)
				(type default)
			)
			(layer "F.Fab")
		)
		(fp_line
			(start 2.500122 -2.500122)
			(end 2.500122 2.500122)
			(stroke
				(width 0.1)
				(type default)
			)
			(layer "F.Fab")
		)
		(fp_line
			(start -1.8034 -2.8702)
			(end -1.8034 -3.6322)
			(stroke
				(width 0.1)
				(type default)
			)
			(layer "F.Fab")
		)
		(fp_line
			(start 0.1778 -3.2385)
			(end 0.1778 -2.8575)
			(stroke
				(width 0.1)
				(type default)
			)
			(layer "F.Fab")
		)
		(fp_poly
			(pts
				(xy -2.921 -1.800098) (xy -3.504184 -1.508506) (xy -3.504184 -2.09169)
			)
			(stroke
				(width 0)
				(type default)
			)
			(fill yes)
			(layer "F.Fab")
		)
		(fp_text user "11"
			(at -2.76352 6.448552 270)
			(unlocked yes)
			(layer "F.SilkS")
			(effects
				(font
					(size 0.635 0.4064)
					(thickness 0.1524)
				)
				(justify left)
			)
		)
		(fp_text user "21"
			(at 3.744468 3.57886 180)
			(unlocked yes)
			(layer "F.SilkS")
			(effects
				(font
					(size 0.635 0.4064)
					(thickness 0.1524)
				)
				(justify left)
			)
		)
		(fp_text user "20"
			(at 2.0828 3.253232 270)
			(unlocked yes)
			(layer "F.SilkS")
			(effects
				(font
					(size 0.635 0.4064)
					(thickness 0.1524)
				)
				(justify left)
			)
		)
		(fp_text user "10"
			(at -6.070092 3.1369 180)
			(unlocked yes)
			(layer "F.SilkS")
			(effects
				(font
					(size 0.635 0.4064)
					(thickness 0.1524)
				)
				(justify left)
			)
		)
		(fp_text user "30"
			(at 3.040888 -2.96926 180)
			(unlocked yes)
			(layer "F.SilkS")
			(effects
				(font
					(size 0.635 0.4064)
					(thickness 0.1524)
				)
				(justify left)
			)
		)
		(fp_text user "31"
			(at 1.60782 -3.119628 270)
			(unlocked yes)
			(layer "F.SilkS")
			(effects
				(font
					(size 0.635 0.4064)
					(thickness 0.1524)
				)
				(justify left)
			)
		)
		(fp_text user "40"
			(at -2.464562 -3.243072 0)
			(unlocked yes)
			(layer "F.SilkS")
			(effects
				(font
					(size 0.635 0.4064)
					(thickness 0.1524)
				)
				(justify left)
			)
		)
		(fp_text user "11"
			(at -2.8702 3.278632 270)
			(unlocked yes)
			(layer "F.Fab")
			(effects
				(font
					(size 0.635 0.4064)
					(thickness 0.1524)
				)
				(justify left)
			)
		)
		(fp_text user "20"
			(at 2.0828 3.253232 270)
			(unlocked yes)
			(layer "F.Fab")
			(effects
				(font
					(size 0.635 0.4064)
					(thickness 0.1524)
				)
				(justify left)
			)
		)
		(fp_text user "10"
			(at -3.253232 2.1336 180)
			(unlocked yes)
			(layer "F.Fab")
			(effects
				(font
					(size 0.635 0.4064)
					(thickness 0.1524)
				)
				(justify left)
			)
		)
		(fp_text user "21"
			(at 3.274568 1.8796 180)
			(unlocked yes)
			(layer "F.Fab")
			(effects
				(font
					(size 0.635 0.4064)
					(thickness 0.1524)
				)
				(justify left)
			)
		)
		(fp_text user "40"
			(at -3.2004 -3.096768 270)
			(unlocked yes)
			(layer "F.Fab")
			(effects
				(font
					(size 0.635 0.4064)
					(thickness 0.1524)
				)
				(justify left)
			)
		)
		(fp_text user "30"
			(at 3.223768 -3.0988 180)
			(unlocked yes)
			(layer "F.Fab")
			(effects
				(font
					(size 0.635 0.4064)
					(thickness 0.1524)
				)
				(justify left)
			)
		)
		(fp_text user "31"
			(at 1.8542 -3.172968 270)
			(unlocked yes)
			(layer "F.Fab")
			(effects
				(font
					(size 0.635 0.4064)
					(thickness 0.1524)
				)
				(justify left)
			)
		)
		(pad "1" smd rect
			(at -2.400046 -1.800098 180)
			(size 0.1778 0.6096)
			(layers "F.Cu" "F.Mask" "F.Paste")
			(net "NC_PVDD11_S3_P1_PWM8")
		)
		(pad "2" smd rect
			(at -2.400046 -1.400048 180)
			(size 0.1778 0.6096)
			(layers "F.Cu" "F.Mask" "F.Paste")
			(net "NC_PVDD11_S3_P1_PWM7")
		)
		(pad "3" smd rect
			(at -2.400046 -0.999998 180)
			(size 0.1778 0.6096)
			(layers "F.Cu" "F.Mask" "F.Paste")
			(net "NC_PVDD11_S3_P1_PWM6")
		)
		(pad "4" smd rect
			(at -2.400046 -0.599948 180)
			(size 0.1778 0.6096)
			(layers "F.Cu" "F.Mask" "F.Paste")
			(net "NC_PVDD11_S3_P1_PWM5")
		)
		(pad "5" smd rect
			(at -2.400046 -0.199898 180)
			(size 0.1778 0.6096)
			(layers "F.Cu" "F.Mask" "F.Paste")
			(net "NC_PVDD11_S3_P1_PWM4")
		)
		(pad "6" smd rect
			(at -2.400046 0.199898 180)
			(size 0.1778 0.6096)
			(layers "F.Cu" "F.Mask" "F.Paste")
			(net "NC_PVDD11_S3_P1_PWM3")
		)
		(pad "7" smd rect
			(at -2.400046 0.599948 180)
			(size 0.1778 0.6096)
			(layers "F.Cu" "F.Mask" "F.Paste")
			(net "PVDD11_S3_P1_PWM2")
		)
		(pad "8" smd rect
			(at -2.400046 0.999998 180)
			(size 0.1778 0.6096)
			(layers "F.Cu" "F.Mask" "F.Paste")
			(net "PVDD11_S3_P1_PWM1")
		)
		(pad "9" smd rect
			(at -2.400046 1.400048 180)
			(size 0.1778 0.6096)
			(layers "F.Cu" "F.Mask" "F.Paste")
			(net "PVDD11_S3_P1_PMSDA_R")
		)
		(pad "10" smd rect
			(at -2.400046 1.800098 180)
			(size 0.1778 0.6096)
			(layers "F.Cu" "F.Mask" "F.Paste")
			(net "PVDD11_S3_P1_PMSCL_R")
		)
		(pad "11" smd rect
			(at -1.800098 2.400046 270)
			(size 0.1778 0.6096)
			(layers "F.Cu" "F.Mask" "F.Paste")
			(net "PVDD11_S3_P1_PMALERT_R")
		)
		(pad "12" smd rect
			(at -1.400048 2.400046 270)
			(size 0.1778 0.6096)
			(layers "F.Cu" "F.Mask" "F.Paste")
			(net "PWRGD_PVDD11_S3_P1_R")
		)
		(pad "13" smd rect
			(at -0.999998 2.400046 270)
			(size 0.1778 0.6096)
			(layers "F.Cu" "F.Mask" "F.Paste")
			(net "PVDD11_S3_P1_EN_R")
		)
		(pad "14" smd rect
			(at -0.599948 2.400046 270)
			(size 0.1778 0.6096)
			(layers "F.Cu" "F.Mask" "F.Paste")
			(net "PVDD11_S3_P1_RESET_N_R")
		)
		(pad "15" smd rect
			(at -0.199898 2.400046 270)
			(size 0.1778 0.6096)
			(layers "F.Cu" "F.Mask" "F.Paste")
			(net "PVDD11_S3_P1_VDDIO")
		)
		(pad "16" smd rect
			(at 0.199898 2.400046 270)
			(size 0.1778 0.6096)
			(layers "F.Cu" "F.Mask" "F.Paste")
			(net "NC_PVDD11_S3_P1_PG1")
		)
		(pad "17" smd rect
			(at 0.599948 2.400046 270)
			(size 0.1778 0.6096)
			(layers "F.Cu" "F.Mask" "F.Paste")
			(net "GND")
		)
		(pad "18" smd rect
			(at 0.999998 2.400046 270)
			(size 0.1778 0.6096)
			(layers "F.Cu" "F.Mask" "F.Paste")
			(net "GND")
		)
		(pad "19" smd rect
			(at 1.400048 2.400046 270)
			(size 0.1778 0.6096)
			(layers "F.Cu" "F.Mask" "F.Paste")
			(net "NC_PVDD11_S3_P1_SVTO")
		)
		(pad "20" smd rect
			(at 1.800098 2.400046 270)
			(size 0.1778 0.6096)
			(layers "F.Cu" "F.Mask" "F.Paste")
			(net "GND")
		)
		(pad "21" smd rect
			(at 2.400046 1.800098 180)
			(size 0.1778 0.6096)
			(layers "F.Cu" "F.Mask" "F.Paste")
			(net "VSENSE_PVDD11_S3_P1_R")
		)
		(pad "22" smd rect
			(at 2.400046 1.400048 180)
			(size 0.1778 0.6096)
			(layers "F.Cu" "F.Mask" "F.Paste")
			(net "VSENSE_VSS_SENSE_C_P1")
		)
		(pad "23" smd rect
			(at 2.400046 0.999998 180)
			(size 0.1778 0.6096)
			(layers "F.Cu" "F.Mask" "F.Paste")
			(net "PVDD11_S3_P1_IMON1")
		)
		(pad "24" smd rect
			(at 2.400046 0.599948 180)
			(size 0.1778 0.6096)
			(layers "F.Cu" "F.Mask" "F.Paste")
			(net "PVDD11_S3_P1_IMON2")
		)
		(pad "25" smd rect
			(at 2.400046 0.199898 180)
			(size 0.1778 0.6096)
			(layers "F.Cu" "F.Mask" "F.Paste")
			(net "NC_PVDD11_S3_P1_IMON3")
		)
		(pad "26" smd rect
			(at 2.400046 -0.199898 180)
			(size 0.1778 0.6096)
			(layers "F.Cu" "F.Mask" "F.Paste")
			(net "NC_PVDD11_S3_P1_IMON4")
		)
		(pad "27" smd rect
			(at 2.400046 -0.599948 180)
			(size 0.1778 0.6096)
			(layers "F.Cu" "F.Mask" "F.Paste")
			(net "NC_PVDD11_S3_P1_IMON5")
		)
		(pad "28" smd rect
			(at 2.400046 -0.999998 180)
			(size 0.1778 0.6096)
			(layers "F.Cu" "F.Mask" "F.Paste")
			(net "NC_PVDD11_S3_P1_IMON6")
		)
		(pad "29" smd rect
			(at 2.400046 -1.400048 180)
			(size 0.1778 0.6096)
			(layers "F.Cu" "F.Mask" "F.Paste")
			(net "NC_PVDD11_S3_P1_IMON7")
		)
		(pad "30" smd rect
			(at 2.400046 -1.800098 180)
			(size 0.1778 0.6096)
			(layers "F.Cu" "F.Mask" "F.Paste")
			(net "NC_PVDD11_S3_P1_IMON8")
		)
		(pad "31" smd rect
			(at 1.800098 -2.400046 270)
			(size 0.1778 0.6096)
			(layers "F.Cu" "F.Mask" "F.Paste")
			(net "GND")
		)
		(pad "32" smd rect
			(at 1.400048 -2.400046 270)
			(size 0.1778 0.6096)
			(layers "F.Cu" "F.Mask" "F.Paste")
			(net "GND")
		)
		(pad "33" smd rect
			(at 0.999998 -2.400046 270)
			(size 0.1778 0.6096)
			(layers "F.Cu" "F.Mask" "F.Paste")
			(net "PVDD11_S3_P1_OCP_N_R")
		)
		(pad "34" smd rect
			(at 0.599948 -2.400046 270)
			(size 0.1778 0.6096)
			(layers "F.Cu" "F.Mask" "F.Paste")
			(net "PVDD11_S3_P1_ADDR_CFG")
		)
		(pad "35" smd rect
			(at 0.199898 -2.400046 270)
			(size 0.1778 0.6096)
			(layers "F.Cu" "F.Mask" "F.Paste")
			(net "PVDD11_S3_P1_TEMP1")
		)
		(pad "36" smd rect
			(at -0.199898 -2.400046 270)
			(size 0.1778 0.6096)
			(layers "F.Cu" "F.Mask" "F.Paste")
			(net "PVDD11_S3_P1_TEMP0")
		)
		(pad "37" smd rect
			(at -0.599948 -2.400046 270)
			(size 0.1778 0.6096)
			(layers "F.Cu" "F.Mask" "F.Paste")
			(net "PVDD11_S3_P1_VMON")
		)
		(pad "38" smd rect
			(at -0.999998 -2.400046 270)
			(size 0.1778 0.6096)
			(layers "F.Cu" "F.Mask" "F.Paste")
			(net "PVDD11_S3_P1_VINSEN")
		)
		(pad "39" smd rect
			(at -1.400048 -2.400046 270)
			(size 0.1778 0.6096)
			(layers "F.Cu" "F.Mask" "F.Paste")
			(net "PVDD11_S3_P1_VCC")
		)
		(pad "40" smd rect
			(at -1.800098 -2.400046 270)
			(size 0.1778 0.6096)
			(layers "F.Cu" "F.Mask" "F.Paste")
			(net "PVDD11_S3_P1_VCCS")
		)
		(pad "TH" smd rect
			(at 0 0 270)
			(size 3.6576 3.6576)
			(layers "F.Cu" "F.Mask" "F.Paste")
			(net "GND")
		)
		(zone
			(layer "F.Cu")
			(hatch none 0.5)
			(connect_pads
				(clearance 0)
			)
			(min_thickness 0.25)
			(keepout
				(tracks not_allowed)
				(vias allowed)
				(pads allowed)
				(copperpour not_allowed)
				(footprints allowed)
			)
			(placement
				(enabled no)
				(sheetname "")
			)
			(fill
				(thermal_gap 0.5)
				(thermal_bridge_width 0.5)
				(island_removal_mode 0)
			)
			(polygon
				(pts
					(xy 160.19653 -348.181168) (xy 160.19653 -350.585278) (xy 164.08273 -350.585278) (xy 164.08273 -350.432878)
					(xy 160.34893 -350.432878) (xy 160.34893 -348.181168)
				)
			)
		)
	)
	(footprint ""
		(layer "F.Cu")
		(at 347.568266 -416.899344 -90)
		(property "Reference" "C6529"
			(at 0 0 270)
			(layer "F.SilkS")
			(hide yes)
			(effects
				(font
					(size 1.27 1.27)
				)
			)
		)
		(property "Value" ""
			(at 0 0 270)
			(layer "F.Fab")
			(effects
				(font
					(size 1.27 1.27)
				)
			)
		)
		(duplicate_pad_numbers_are_jumpers no)
		(fp_line
			(start -0.299974 0.150114)
			(end -0.299974 -0.150114)
			(stroke
				(width 0.1)
				(type default)
			)
			(layer "F.Fab")
		)
		(fp_line
			(start 0.299974 0.150114)
			(end -0.299974 0.150114)
			(stroke
				(width 0.1)
				(type default)
			)
			(layer "F.Fab")
		)
		(fp_line
			(start -0.299974 -0.150114)
			(end 0.299974 -0.150114)
			(stroke
				(width 0.1)
				(type default)
			)
			(layer "F.Fab")
		)
		(fp_line
			(start 0.299974 -0.150114)
			(end 0.299974 0.150114)
			(stroke
				(width 0.1)
				(type default)
			)
			(layer "F.Fab")
		)
		(pad "1" smd rect
			(at -0.2667 0 270)
			(size 0.3048 0.381)
			(layers "F.Cu" "F.Mask" "F.Paste")
			(net "P5E_CPU0_P0_TX_BUF_C_DP<14>")
		)
		(pad "2" smd rect
			(at 0.2667 0 270)
			(size 0.3048 0.381)
			(layers "F.Cu" "F.Mask" "F.Paste")
			(net "P5E_CPU0_P0_TX_BUF_DP<14>")
		)
	)
)
